(kicad_pcb
	(version 20260206)
	(generator "pcbnew")
	(generator_version "10.0")
	(general
		(thickness 1.6)
		(legacy_teardrops no)
	)
	(paper "A4")
	(title_block
		(title "12092022_DA0F0TFB6D0_F0T_FAN_BOARD_MP5048_D_brd_v02_OCP.brd")
		(comment 1 "Grand Teton / footprints 786-791 of 924")
	)
	(layers
		(0 "F.Cu" signal "TOP")
		(4 "In1.Cu" signal "GND")
		(6 "In2.Cu" signal "IN1")
		(8 "In3.Cu" signal "IN2")
		(10 "In4.Cu" signal "GND1")
		(2 "B.Cu" signal "BOTTOM")
		(9 "F.Adhes" user "F.Adhesive")
		(11 "B.Adhes" user "B.Adhesive")
		(13 "F.Paste" user "Package Geometry/Pastemask Top")
		(15 "B.Paste" user "Package Geometry/Pastemask Bottom")
		(5 "F.SilkS" user "Ref Des/Silkscreen Top")
		(7 "B.SilkS" user "Ref Des/Silkscreen Bottom")
		(1 "F.Mask" user "Board Geometry/Soldermask Top")
		(3 "B.Mask" user "Board Geometry/Soldermask Bottom")
		(17 "Dwgs.User" user "User.Drawings")
		(19 "Cmts.User" user "User.Comments")
		(21 "Eco1.User" user "User.Eco1")
		(23 "Eco2.User" user "User.Eco2")
		(25 "Edge.Cuts" user "Board Geometry/Outline")
		(27 "Margin" user)
		(31 "F.CrtYd" user "Package Geometry/Place Bound Top")
		(29 "B.CrtYd" user "Package Geometry/Place Bound Bottom")
		(35 "F.Fab" user "Ref Des/Assembly Top")
		(33 "B.Fab" user "Ref Des/Assembly Bottom")
	)
	(footprint ""
		(layer "B.Cu")
		(at 17.653 -133.096 180)
		(property "Reference" "R5439"
			(at 0 0 0)
			(layer "B.SilkS")
			(hide yes)
			(effects
				(font
					(size 1.27 1.27)
				)
				(justify mirror)
			)
		)
		(property "Value" ""
			(at 0 0 0)
			(layer "B.Fab")
			(effects
				(font
					(size 1.27 1.27)
				)
				(justify mirror)
			)
		)
		(duplicate_pad_numbers_are_jumpers no)
		(fp_line
			(start 0.7874 0.4064)
			(end 0.7874 -0.4064)
			(stroke
				(width 0.1524)
				(type default)
			)
			(layer "B.SilkS")
		)
		(fp_line
			(start 0.7874 -0.4064)
			(end -0.7874 -0.4064)
			(stroke
				(width 0.1524)
				(type default)
			)
			(layer "B.SilkS")
		)
		(fp_line
			(start -0.7874 0.4064)
			(end 0.7874 0.4064)
			(stroke
				(width 0.1524)
				(type default)
			)
			(layer "B.SilkS")
		)
		(fp_line
			(start -0.7874 -0.4064)
			(end -0.7874 0.4064)
			(stroke
				(width 0.1524)
				(type default)
			)
			(layer "B.SilkS")
		)
		(fp_line
			(start 0.67945 0.3048)
			(end 0.67945 -0.305054)
			(stroke
				(width 0.1)
				(type default)
			)
			(layer "B.Fab")
		)
		(fp_line
			(start 0.67945 -0.305054)
			(end 0.12065 -0.305054)
			(stroke
				(width 0.1)
				(type default)
			)
			(layer "B.Fab")
		)
		(fp_line
			(start 0.12065 0.3048)
			(end 0.67945 0.3048)
			(stroke
				(width 0.1)
				(type default)
			)
			(layer "B.Fab")
		)
		(fp_line
			(start 0.12065 0.2794)
			(end 0.12065 0.3048)
			(stroke
				(width 0.1)
				(type default)
			)
			(layer "B.Fab")
		)
		(fp_line
			(start 0.12065 -0.2794)
			(end -0.12065 -0.2794)
			(stroke
				(width 0.1)
				(type default)
			)
			(layer "B.Fab")
		)
		(fp_line
			(start 0.12065 -0.305054)
			(end 0.12065 -0.2794)
			(stroke
				(width 0.1)
				(type default)
			)
			(layer "B.Fab")
		)
		(fp_line
			(start -0.120396 0.3048)
			(end -0.120396 0.2794)
			(stroke
				(width 0.1)
				(type default)
			)
			(layer "B.Fab")
		)
		(fp_line
			(start -0.120396 0.2794)
			(end 0.12065 0.2794)
			(stroke
				(width 0.1)
				(type default)
			)
			(layer "B.Fab")
		)
		(fp_line
			(start -0.12065 -0.2794)
			(end -0.12065 -0.3048)
			(stroke
				(width 0.1)
				(type default)
			)
			(layer "B.Fab")
		)
		(fp_line
			(start -0.12065 -0.3048)
			(end -0.67945 -0.3048)
			(stroke
				(width 0.1)
				(type default)
			)
			(layer "B.Fab")
		)
		(fp_line
			(start -0.67945 0.3048)
			(end -0.120396 0.3048)
			(stroke
				(width 0.1)
				(type default)
			)
			(layer "B.Fab")
		)
		(fp_line
			(start -0.67945 -0.3048)
			(end -0.67945 0.3048)
			(stroke
				(width 0.1)
				(type default)
			)
			(layer "B.Fab")
		)
		(pad "1" smd rect
			(at 0.40005 0 180)
			(size 0.4572 0.508)
			(layers "B.Cu" "B.Mask" "B.Paste")
			(net "FAN_6_TACH_OL")
		)
		(pad "2" smd rect
			(at -0.40005 0 180)
			(size 0.4572 0.508)
			(layers "B.Cu" "B.Mask" "B.Paste")
			(net "GND")
		)
	)
	(footprint ""
		(layer "B.Cu")
		(at 37.587428 -78.416912 90)
		(property "Reference" "PC16"
			(at 0 0 90)
			(layer "B.SilkS")
			(hide yes)
			(effects
				(font
					(size 1.27 1.27)
				)
				(justify mirror)
			)
		)
		(property "Value" ""
			(at 0 0 90)
			(layer "B.Fab")
			(effects
				(font
					(size 1.27 1.27)
				)
				(justify mirror)
			)
		)
		(duplicate_pad_numbers_are_jumpers no)
		(fp_line
			(start 1.524 -0.762)
			(end -1.524 -0.762)
			(stroke
				(width 0.1524)
				(type default)
			)
			(layer "B.SilkS")
		)
		(fp_line
			(start -1.524 -0.762)
			(end -1.524 0.762)
			(stroke
				(width 0.1524)
				(type default)
			)
			(layer "B.SilkS")
		)
		(fp_line
			(start 1.524 0.762)
			(end 1.524 -0.762)
			(stroke
				(width 0.1524)
				(type default)
			)
			(layer "B.SilkS")
		)
		(fp_line
			(start -1.524 0.762)
			(end 1.524 0.762)
			(stroke
				(width 0.1524)
				(type default)
			)
			(layer "B.SilkS")
		)
		(fp_line
			(start 1.1049 -0.724916)
			(end 1.1049 0.724916)
			(stroke
				(width 0.1)
				(type default)
			)
			(layer "B.Fab")
		)
		(fp_line
			(start -1.1049 -0.724916)
			(end 1.1049 -0.724916)
			(stroke
				(width 0.1)
				(type default)
			)
			(layer "B.Fab")
		)
		(fp_line
			(start 1.1049 0.724916)
			(end -1.1049 0.724916)
			(stroke
				(width 0.1)
				(type default)
			)
			(layer "B.Fab")
		)
		(fp_line
			(start -1.1049 0.724916)
			(end -1.1049 -0.724916)
			(stroke
				(width 0.1)
				(type default)
			)
			(layer "B.Fab")
		)
		(pad "1" smd rect
			(at 0.889 0 90)
			(size 1.016 1.27)
			(layers "B.Cu" "B.Mask" "B.Paste")
			(net "P52V_HSC")
		)
		(pad "2" smd rect
			(at -0.889 0 90)
			(size 1.016 1.27)
			(layers "B.Cu" "B.Mask" "B.Paste")
			(net "GND")
		)
	)
	(footprint ""
		(layer "B.Cu")
		(at 5.50799 -90.371168 -90)
		(property "Reference" "PD11"
			(at 4.7752 -3.749548 270)
			(unlocked yes)
			(layer "B.SilkS")
			(effects
				(font
					(size 0.7874 0.5842)
					(thickness 0.1524)
				)
				(justify left mirror)
			)
		)
		(property "Value" ""
			(at 0 0 90)
			(layer "B.Fab")
			(effects
				(font
					(size 1.27 1.27)
				)
				(justify mirror)
			)
		)
		(duplicate_pad_numbers_are_jumpers no)
		(fp_line
			(start -5.334 3.109976)
			(end -4.8133 3.109976)
			(stroke
				(width 0.1524)
				(type default)
			)
			(layer "B.SilkS")
		)
		(fp_line
			(start -5.334 3.109976)
			(end -5.334 0)
			(stroke
				(width 0.1524)
				(type default)
			)
			(layer "B.SilkS")
		)
		(fp_line
			(start -5.207 3.109976)
			(end -5.207 -3.109976)
			(stroke
				(width 0.1524)
				(type default)
			)
			(layer "B.SilkS")
		)
		(fp_line
			(start -5.1308 3.109976)
			(end -5.1308 -3.109976)
			(stroke
				(width 0.1524)
				(type default)
			)
			(layer "B.SilkS")
		)
		(fp_line
			(start -5.0292 3.109976)
			(end -5.0292 -3.109976)
			(stroke
				(width 0.1524)
				(type default)
			)
			(layer "B.SilkS")
		)
		(fp_line
			(start -4.9276 3.109976)
			(end -4.9276 -3.109976)
			(stroke
				(width 0.1524)
				(type default)
			)
			(layer "B.SilkS")
		)
		(fp_line
			(start -4.826 3.109976)
			(end 4.826 3.109976)
			(stroke
				(width 0.1524)
				(type default)
			)
			(layer "B.SilkS")
		)
		(fp_line
			(start 4.826 3.109976)
			(end 4.826 0)
			(stroke
				(width 0.1524)
				(type default)
			)
			(layer "B.SilkS")
		)
		(fp_line
			(start -1.143 1.397)
			(end -1.143 -1.397)
			(stroke
				(width 0.1524)
				(type default)
			)
			(layer "B.SilkS")
		)
		(fp_line
			(start 1.016 1.016)
			(end -1.016 0)
			(stroke
				(width 0.1524)
				(type default)
			)
			(layer "B.SilkS")
		)
		(fp_line
			(start -5.334 0)
			(end -5.334 -3.109976)
			(stroke
				(width 0.1524)
				(type default)
			)
			(layer "B.SilkS")
		)
		(fp_line
			(start -4.826 0)
			(end -4.826 3.109976)
			(stroke
				(width 0.1524)
				(type default)
			)
			(layer "B.SilkS")
		)
		(fp_line
			(start -1.143 0)
			(end -1.8034 0)
			(stroke
				(width 0.1524)
				(type default)
			)
			(layer "B.SilkS")
		)
		(fp_line
			(start -1.143 0)
			(end 1.016 -1.016)
			(stroke
				(width 0.1524)
				(type default)
			)
			(layer "B.SilkS")
		)
		(fp_line
			(start 1.0922 0)
			(end 1.7018 0)
			(stroke
				(width 0.1524)
				(type default)
			)
			(layer "B.SilkS")
		)
		(fp_line
			(start 4.826 0)
			(end 4.826 -3.109976)
			(stroke
				(width 0.1524)
				(type default)
			)
			(layer "B.SilkS")
		)
		(fp_line
			(start 1.016 -1.016)
			(end 1.016 1.016)
			(stroke
				(width 0.1524)
				(type default)
			)
			(layer "B.SilkS")
		)
		(fp_line
			(start -4.826 -3.109976)
			(end -4.826 0)
			(stroke
				(width 0.1524)
				(type default)
			)
			(layer "B.SilkS")
		)
		(fp_line
			(start -4.8133 -3.109976)
			(end -5.3467 -3.109976)
			(stroke
				(width 0.1524)
				(type default)
			)
			(layer "B.SilkS")
		)
		(fp_line
			(start 4.826 -3.109976)
			(end -4.826 -3.109976)
			(stroke
				(width 0.1524)
				(type default)
			)
			(layer "B.SilkS")
		)
		(fp_line
			(start -3.554984 3.109976)
			(end 3.554984 3.109976)
			(stroke
				(width 0.1)
				(type default)
			)
			(layer "B.Fab")
		)
		(fp_line
			(start 3.554984 3.109976)
			(end 3.554984 -3.109976)
			(stroke
				(width 0.1)
				(type default)
			)
			(layer "B.Fab")
		)
		(fp_line
			(start -1.143 1.397)
			(end -1.143 -1.397)
			(stroke
				(width 0.1)
				(type default)
			)
			(layer "B.Fab")
		)
		(fp_line
			(start 1.016 1.016)
			(end -1.016 0)
			(stroke
				(width 0.1)
				(type default)
			)
			(layer "B.Fab")
		)
		(fp_line
			(start -1.143 0)
			(end -1.8034 0)
			(stroke
				(width 0.1)
				(type default)
			)
			(layer "B.Fab")
		)
		(fp_line
			(start -1.143 0)
			(end 1.016 -1.016)
			(stroke
				(width 0.1)
				(type default)
			)
			(layer "B.Fab")
		)
		(fp_line
			(start 1.0922 0)
			(end 1.7018 0)
			(stroke
				(width 0.1)
				(type default)
			)
			(layer "B.Fab")
		)
		(fp_line
			(start 1.016 -1.016)
			(end 1.016 1.016)
			(stroke
				(width 0.1)
				(type default)
			)
			(layer "B.Fab")
		)
		(fp_line
			(start -3.554984 -3.109976)
			(end -3.554984 3.109976)
			(stroke
				(width 0.1)
				(type default)
			)
			(layer "B.Fab")
		)
		(fp_line
			(start 3.554984 -3.109976)
			(end -3.554984 -3.109976)
			(stroke
				(width 0.1)
				(type default)
			)
			(layer "B.Fab")
		)
		(fp_text user "-"
			(at -6.682232 -1.76276 90)
			(unlocked yes)
			(layer "B.SilkS")
			(effects
				(font
					(size 1.905 1.4224)
					(thickness 0.1524)
				)
				(justify left mirror)
			)
		)
		(fp_text user "+"
			(at 4.620768 -1.76276 90)
			(unlocked yes)
			(layer "B.SilkS")
			(effects
				(font
					(size 1.905 1.4224)
					(thickness 0.1524)
				)
				(justify left mirror)
			)
		)
		(fp_text user "-"
			(at -6.6802 0.22225 90)
			(unlocked yes)
			(layer "B.Fab")
			(effects
				(font
					(size 1.905 1.4224)
					(thickness 0.1524)
				)
				(justify left mirror)
			)
		)
		(fp_text user "+"
			(at 4.5466 0.19685 90)
			(unlocked yes)
			(layer "B.Fab")
			(effects
				(font
					(size 1.905 1.4224)
					(thickness 0.1524)
				)
				(justify left mirror)
			)
		)
		(pad "A" smd rect
			(at 3.400044 0 270)
			(size 2.5146 3.302)
			(layers "B.Cu" "B.Mask" "B.Paste")
			(net "GND")
		)
		(pad "C" smd rect
			(at -3.400044 0 270)
			(size 2.5146 3.302)
			(layers "B.Cu" "B.Mask" "B.Paste")
			(net "P52V_FAN_5")
		)
	)
	(footprint ""
		(layer "B.Cu")
		(at 44.704 -47.625 180)
		(property "Reference" "C2106"
			(at 0 0 0)
			(layer "B.SilkS")
			(hide yes)
			(effects
				(font
					(size 1.27 1.27)
				)
				(justify mirror)
			)
		)
		(property "Value" ""
			(at 0 0 0)
			(layer "B.Fab")
			(effects
				(font
					(size 1.27 1.27)
				)
				(justify mirror)
			)
		)
		(duplicate_pad_numbers_are_jumpers no)
		(fp_line
			(start 2.2098 0.9398)
			(end 2.2098 -0.9398)
			(stroke
				(width 0.1524)
				(type default)
			)
			(layer "B.SilkS")
		)
		(fp_line
			(start 2.2098 -0.9398)
			(end -2.2098 -0.9398)
			(stroke
				(width 0.1524)
				(type default)
			)
			(layer "B.SilkS")
		)
		(fp_line
			(start -2.2098 0.9398)
			(end 2.2098 0.9398)
			(stroke
				(width 0.1524)
				(type default)
			)
			(layer "B.SilkS")
		)
		(fp_line
			(start -2.2098 -0.9398)
			(end -2.2098 0.9398)
			(stroke
				(width 0.1524)
				(type default)
			)
			(layer "B.SilkS")
		)
		(fp_line
			(start 1.700022 0.899922)
			(end 1.700022 -0.899922)
			(stroke
				(width 0.1)
				(type default)
			)
			(layer "B.Fab")
		)
		(fp_line
			(start 1.700022 -0.899922)
			(end -1.700022 -0.899922)
			(stroke
				(width 0.1)
				(type default)
			)
			(layer "B.Fab")
		)
		(fp_line
			(start -1.700022 0.899922)
			(end 1.700022 0.899922)
			(stroke
				(width 0.1)
				(type default)
			)
			(layer "B.Fab")
		)
		(fp_line
			(start -1.700022 -0.899922)
			(end -1.700022 0.899922)
			(stroke
				(width 0.1)
				(type default)
			)
			(layer "B.Fab")
		)
		(pad "1" smd rect
			(at 1.4732 0 180)
			(size 1.1684 1.5748)
			(layers "B.Cu" "B.Mask" "B.Paste")
			(net "P52V_FAN_3")
		)
		(pad "2" smd rect
			(at -1.4732 0 180)
			(size 1.1684 1.5748)
			(layers "B.Cu" "B.Mask" "B.Paste")
			(net "GND")
		)
	)
	(footprint ""
		(layer "B.Cu")
		(at 33.401 -64.837056 90)
		(property "Reference" "PR46"
			(at 0 0 90)
			(layer "B.SilkS")
			(hide yes)
			(effects
				(font
					(size 1.27 1.27)
				)
				(justify mirror)
			)
		)
		(property "Value" ""
			(at 0 0 90)
			(layer "B.Fab")
			(effects
				(font
					(size 1.27 1.27)
				)
				(justify mirror)
			)
		)
		(duplicate_pad_numbers_are_jumpers no)
		(fp_line
			(start 0.7874 -0.4064)
			(end -0.7874 -0.4064)
			(stroke
				(width 0.1524)
				(type default)
			)
			(layer "B.SilkS")
		)
		(fp_line
			(start -0.7874 -0.4064)
			(end -0.7874 0.4064)
			(stroke
				(width 0.1524)
				(type default)
			)
			(layer "B.SilkS")
		)
		(fp_line
			(start 0.7874 0.4064)
			(end 0.7874 -0.4064)
			(stroke
				(width 0.1524)
				(type default)
			)
			(layer "B.SilkS")
		)
		(fp_line
			(start -0.7874 0.4064)
			(end 0.7874 0.4064)
			(stroke
				(width 0.1524)
				(type default)
			)
			(layer "B.SilkS")
		)
		(fp_line
			(start 0.67945 -0.305054)
			(end 0.12065 -0.305054)
			(stroke
				(width 0.1)
				(type default)
			)
			(layer "B.Fab")
		)
		(fp_line
			(start 0.12065 -0.305054)
			(end 0.12065 -0.2794)
			(stroke
				(width 0.1)
				(type default)
			)
			(layer "B.Fab")
		)
		(fp_line
			(start -0.12065 -0.3048)
			(end -0.67945 -0.3048)
			(stroke
				(width 0.1)
				(type default)
			)
			(layer "B.Fab")
		)
		(fp_line
			(start -0.67945 -0.3048)
			(end -0.67945 0.3048)
			(stroke
				(width 0.1)
				(type default)
			)
			(layer "B.Fab")
		)
		(fp_line
			(start 0.12065 -0.2794)
			(end -0.12065 -0.2794)
			(stroke
				(width 0.1)
				(type default)
			)
			(layer "B.Fab")
		)
		(fp_line
			(start -0.12065 -0.2794)
			(end -0.12065 -0.3048)
			(stroke
				(width 0.1)
				(type default)
			)
			(layer "B.Fab")
		)
		(fp_line
			(start 0.12065 0.2794)
			(end 0.12065 0.3048)
			(stroke
				(width 0.1)
				(type default)
			)
			(layer "B.Fab")
		)
		(fp_line
			(start -0.120396 0.2794)
			(end 0.12065 0.2794)
			(stroke
				(width 0.1)
				(type default)
			)
			(layer "B.Fab")
		)
		(fp_line
			(start 0.67945 0.3048)
			(end 0.67945 -0.305054)
			(stroke
				(width 0.1)
				(type default)
			)
			(layer "B.Fab")
		)
		(fp_line
			(start 0.12065 0.3048)
			(end 0.67945 0.3048)
			(stroke
				(width 0.1)
				(type default)
			)
			(layer "B.Fab")
		)
		(fp_line
			(start -0.120396 0.3048)
			(end -0.120396 0.2794)
			(stroke
				(width 0.1)
				(type default)
			)
			(layer "B.Fab")
		)
		(fp_line
			(start -0.67945 0.3048)
			(end -0.120396 0.3048)
			(stroke
				(width 0.1)
				(type default)
			)
			(layer "B.Fab")
		)
		(pad "1" smd circle
			(at 0.40005 0 270)
			(size 0 0)
			(layers "B.Cu" "B.Mask" "B.Paste")
			(net "GND")
		)
		(pad "2" smd circle
			(at -0.40005 0 270)
			(size 0 0)
			(layers "B.Cu" "B.Mask" "B.Paste")
			(net "FAN_3_IMON")
		)
	)
	(footprint ""
		(layer "B.Cu")
		(at 44.621958 -239.1664 180)
		(property "Reference" "PC24"
			(at 0 0 0)
			(layer "B.SilkS")
			(hide yes)
			(effects
				(font
					(size 1.27 1.27)
				)
				(justify mirror)
			)
		)
		(property "Value" ""
			(at 0 0 0)
			(layer "B.Fab")
			(effects
				(font
					(size 1.27 1.27)
				)
				(justify mirror)
			)
		)
		(duplicate_pad_numbers_are_jumpers no)
		(fp_line
			(start 1.524 0.762)
			(end 1.524 -0.762)
			(stroke
				(width 0.1524)
				(type default)
			)
			(layer "B.SilkS")
		)
		(fp_line
			(start 1.524 -0.762)
			(end -1.524 -0.762)
			(stroke
				(width 0.1524)
				(type default)
			)
			(layer "B.SilkS")
		)
		(fp_line
			(start -1.524 0.762)
			(end 1.524 0.762)
			(stroke
				(width 0.1524)
				(type default)
			)
			(layer "B.SilkS")
		)
		(fp_line
			(start -1.524 -0.762)
			(end -1.524 0.762)
			(stroke
				(width 0.1524)
				(type default)
			)
			(layer "B.SilkS")
		)
		(fp_line
			(start 1.1049 0.724916)
			(end -1.1049 0.724916)
			(stroke
				(width 0.1)
				(type default)
			)
			(layer "B.Fab")
		)
		(fp_line
			(start 1.1049 -0.724916)
			(end 1.1049 0.724916)
			(stroke
				(width 0.1)
				(type default)
			)
			(layer "B.Fab")
		)
		(fp_line
			(start -1.1049 0.724916)
			(end -1.1049 -0.724916)
			(stroke
				(width 0.1)
				(type default)
			)
			(layer "B.Fab")
		)
		(fp_line
			(start -1.1049 -0.724916)
			(end 1.1049 -0.724916)
			(stroke
				(width 0.1)
				(type default)
			)
			(layer "B.Fab")
		)
		(pad "1" smd rect
			(at 0.889 0 180)
			(size 1.016 1.27)
			(layers "B.Cu" "B.Mask" "B.Paste")
			(net "P52V_FAN_1")
		)
		(pad "2" smd rect
			(at -0.889 0 180)
			(size 1.016 1.27)
			(layers "B.Cu" "B.Mask" "B.Paste")
			(net "GND")
		)
	)
)
